(kicad_pcb
	(version 20241229)
	(generator "pcbnew")
	(generator_version "9.0")
	(general
		(thickness 1.552)
		(legacy_teardrops no)
	)
	(paper "A4")
	(title_block
		(date "2023-07-25")
		(rev "1.1.4")
		(comment 9 "footprints 253-257 of 379")
	)
	(layers
		(0 "F.Cu" signal)
		(4 "In1.Cu" signal)
		(6 "In2.Cu" signal)
		(8 "In3.Cu" signal)
		(10 "In4.Cu" signal)
		(12 "In5.Cu" signal)
		(14 "In6.Cu" signal)
		(2 "B.Cu" signal)
		(9 "F.Adhes" user "F.Adhesive")
		(11 "B.Adhes" user "B.Adhesive")
		(13 "F.Paste" user)
		(15 "B.Paste" user)
		(5 "F.SilkS" user "F.Silkscreen")
		(7 "B.SilkS" user "B.Silkscreen")
		(1 "F.Mask" user)
		(3 "B.Mask" user)
		(17 "Dwgs.User" user "User.Drawings")
		(19 "Cmts.User" user "User.Comments")
		(21 "Eco1.User" user "User.Eco1")
		(23 "Eco2.User" user "User.Eco2")
		(25 "Edge.Cuts" user)
		(27 "Margin" user)
		(31 "F.CrtYd" user "F.Courtyard")
		(29 "B.CrtYd" user "B.Courtyard")
		(35 "F.Fab" user)
		(33 "B.Fab" user)
	)
	(footprint "antmicro-footprints:R_0402_1005Metric"
		(layer "B.Cu")
		(at 155.33 60.25 -90)
		(descr "Resistor SMD 0402")
		(tags "resistor SMD 0402")
		(property "Reference" "R11"
			(at -0.91 -1.3 90)
			(layer "B.SilkS")
			(effects
				(font
					(size 0.65 0.65)
					(thickness 0.15)
				)
				(justify left bottom mirror)
			)
		)
		(property "Value" "R_5k1_0402"
			(at 0 -1.4 90)
			(layer "B.Fab")
			(hide yes)
			(effects
				(font
					(size 0.7 0.7)
					(thickness 0.15)
				)
				(justify left bottom mirror)
			)
		)
		(property "Datasheet" "https://www.bourns.com/docs/product-datasheets/cr.pdf"
			(at 0 0 270)
			(layer "F.Fab")
			(hide yes)
			(effects
				(font
					(size 1.27 1.27)
					(thickness 0.15)
				)
			)
		)
		(property "Description" "SMD Chip Resistor, 5.1 kohm, ± 1%, 63 mW, 0402 [1005 Metric], Thick Film, General Purpose"
			(at 0 0 270)
			(layer "F.Fab")
			(hide yes)
			(effects
				(font
					(size 1.27 1.27)
					(thickness 0.15)
				)
			)
		)
		(property "Author" "Antmicro"
			(at 95.08 215.58 0)
			(layer "B.Fab")
			(hide yes)
			(effects
				(font
					(size 1 1)
					(thickness 0.15)
				)
				(justify mirror)
			)
		)
		(property "License" "Apache-2.0"
			(at 95.08 215.58 0)
			(layer "B.Fab")
			(hide yes)
			(effects
				(font
					(size 1 1)
					(thickness 0.15)
				)
				(justify mirror)
			)
		)
		(property "MPN" "CR0402-FX-5101GLF"
			(at 95.08 215.58 0)
			(layer "B.Fab")
			(hide yes)
			(effects
				(font
					(size 1 1)
					(thickness 0.15)
				)
				(justify mirror)
			)
		)
		(property "Manufacturer" "Bourns"
			(at 95.08 215.58 0)
			(layer "B.Fab")
			(hide yes)
			(effects
				(font
					(size 1 1)
					(thickness 0.15)
				)
				(justify mirror)
			)
		)
		(property "Tolerance" "1%"
			(at 95.08 215.58 0)
			(layer "B.Fab")
			(hide yes)
			(effects
				(font
					(size 1 1)
					(thickness 0.15)
				)
				(justify mirror)
			)
		)
		(property "Val" "5k1"
			(at 95.08 215.58 0)
			(layer "B.Fab")
			(hide yes)
			(effects
				(font
					(size 1 1)
					(thickness 0.15)
				)
				(justify mirror)
			)
		)
		(sheetname "/Peripherals/")
		(sheetfile "peripherals.kicad_sch")
		(attr smd)
		(fp_rect
			(start -0.925 0.47)
			(end 0.925 -0.47)
			(stroke
				(width 0.05)
				(type default)
			)
			(fill no)
			(layer "B.CrtYd")
		)
		(fp_rect
			(start -0.5 0.25)
			(end 0.5 -0.25)
			(stroke
				(width 0.15)
				(type solid)
			)
			(fill no)
			(layer "B.Fab")
		)
		(fp_text user "License: Apache-2.0"
			(at -0.95 -5.169 90)
			(layer "B.Fab")
			(effects
				(font
					(size 0.7 0.7)
					(thickness 0.15)
				)
				(justify left bottom mirror)
			)
		)
		(fp_text user "${REFERENCE}"
			(at -0.95 -3.168 90)
			(layer "B.Fab")
			(effects
				(font
					(size 0.7 0.7)
					(thickness 0.15)
				)
				(justify left bottom mirror)
			)
		)
		(fp_text user "Author: Antmicro"
			(at -0.95 -4.169 90)
			(layer "B.Fab")
			(effects
				(font
					(size 0.7 0.7)
					(thickness 0.15)
				)
				(justify left bottom mirror)
			)
		)
		(pad "1" smd roundrect
			(at -0.48 0 270)
			(size 0.59 0.64)
			(layers "B.Cu" "B.Mask" "B.Paste")
			(roundrect_rratio 0.25)
			(net 1 "GND")
			(pintype "passive")
		)
		(pad "2" smd roundrect
			(at 0.48 0 270)
			(size 0.59 0.64)
			(layers "B.Cu" "B.Mask" "B.Paste")
			(roundrect_rratio 0.25)
			(net 311 "Net-(J1-CC_{1})")
			(pintype "passive")
		)
	)
	(footprint "antmicro-footprints:R_Array_4x0402"
		(layer "B.Cu")
		(at 124.56 65.24 -90)
		(property "Reference" "R50"
			(at 0.1 1.03 90)
			(layer "B.SilkS")
			(effects
				(font
					(size 0.65 0.65)
					(thickness 0.15)
				)
				(justify left bottom mirror)
			)
		)
		(property "Value" "R_4x51R_0402_array"
			(at -1.5 -2 90)
			(layer "B.Fab")
			(hide yes)
			(effects
				(font
					(size 0.7 0.7)
					(thickness 0.15)
				)
				(justify left bottom mirror)
			)
		)
		(property "Datasheet" "http://industrial.panasonic.com/cdbs/www-data/pdf/AOC0000/AOC0000C14.pdf"
			(at 0 0 270)
			(layer "F.Fab")
			(hide yes)
			(effects
				(font
					(size 1.27 1.27)
					(thickness 0.15)
				)
			)
		)
		(property "Description" "Fixed Network Resistor, 51 ohm, Isolated, 4 Resistors, 0804 [2010 Metric], Convex, ± 5%"
			(at 0 0 270)
			(layer "F.Fab")
			(hide yes)
			(effects
				(font
					(size 1.27 1.27)
					(thickness 0.15)
				)
			)
		)
		(property "Author" "Antmicro"
			(at 59.32 189.8 0)
			(layer "B.Fab")
			(hide yes)
			(effects
				(font
					(size 1 1)
					(thickness 0.15)
				)
				(justify mirror)
			)
		)
		(property "License" "Apache-2.0"
			(at 59.32 189.8 0)
			(layer "B.Fab")
			(hide yes)
			(effects
				(font
					(size 1 1)
					(thickness 0.15)
				)
				(justify mirror)
			)
		)
		(property "MPN" "EXB28V510JX"
			(at 59.32 189.8 0)
			(layer "B.Fab")
			(hide yes)
			(effects
				(font
					(size 1 1)
					(thickness 0.15)
				)
				(justify mirror)
			)
		)
		(property "Manufacturer" "Panasonic"
			(at 59.32 189.8 0)
			(layer "B.Fab")
			(hide yes)
			(effects
				(font
					(size 1 1)
					(thickness 0.15)
				)
				(justify mirror)
			)
		)
		(property "Val" "R_4x51R_0402"
			(at 59.32 189.8 0)
			(layer "B.Fab")
			(hide yes)
			(effects
				(font
					(size 1 1)
					(thickness 0.15)
				)
				(justify mirror)
			)
		)
		(sheetname "/DDR3/")
		(sheetfile "ddr3.kicad_sch")
		(attr smd)
		(fp_line
			(start -1.17 0.5)
			(end -1.17 -0.498)
			(stroke
				(width 0.15)
				(type solid)
			)
			(layer "B.SilkS")
		)
		(fp_line
			(start 1.167 -0.498)
			(end 1.167 0.5)
			(stroke
				(width 0.15)
				(type solid)
			)
			(layer "B.SilkS")
		)
		(fp_rect
			(start -1.2 0.9)
			(end 1.2 -0.9)
			(stroke
				(width 0.05)
				(type solid)
			)
			(fill no)
			(layer "B.CrtYd")
		)
		(fp_line
			(start -1 0.5)
			(end 0.998 0.5)
			(stroke
				(width 0.15)
				(type solid)
			)
			(layer "B.Fab")
		)
		(fp_line
			(start 0.998 0.5)
			(end 0.998 -0.498)
			(stroke
				(width 0.15)
				(type solid)
			)
			(layer "B.Fab")
		)
		(fp_line
			(start -1 -0.498)
			(end -1 0.5)
			(stroke
				(width 0.15)
				(type solid)
			)
			(layer "B.Fab")
		)
		(fp_line
			(start 0.998 -0.498)
			(end -1 -0.498)
			(stroke
				(width 0.15)
				(type solid)
			)
			(layer "B.Fab")
		)
		(pad "1" smd roundrect
			(at -0.802 -0.45 270)
			(size 0.4 0.5)
			(layers "B.Cu" "B.Mask" "B.Paste")
			(roundrect_rratio 0.25)
			(net 166 "/DDR3/DDR3_ODT")
			(pinfunction "R1.1")
			(pintype "passive")
		)
		(pad "2" smd roundrect
			(at -0.272 -0.45 270)
			(size 0.4 0.5)
			(layers "B.Cu" "B.Mask" "B.Paste")
			(roundrect_rratio 0.25)
			(net 161 "/DDR3/~{DDR3_CAS}")
			(pinfunction "R2.1")
			(pintype "passive")
		)
		(pad "3" smd roundrect
			(at 0.27 -0.45 270)
			(size 0.4 0.5)
			(layers "B.Cu" "B.Mask" "B.Paste")
			(roundrect_rratio 0.25)
			(net 162 "/DDR3/~{DDR3_RAS}")
			(pinfunction "R3.1")
			(pintype "passive")
		)
		(pad "4" smd roundrect
			(at 0.8 -0.45 270)
			(size 0.4 0.5)
			(layers "B.Cu" "B.Mask" "B.Paste")
			(roundrect_rratio 0.25)
			(net 165 "/DDR3/DDR3_CKE")
			(pinfunction "R4.1")
			(pintype "passive")
		)
		(pad "5" smd roundrect
			(at 0.8 0.452 270)
			(size 0.4 0.5)
			(layers "B.Cu" "B.Mask" "B.Paste")
			(roundrect_rratio 0.25)
			(net 6 "Vtt")
			(pinfunction "R4.2")
			(pintype "passive")
		)
		(pad "6" smd roundrect
			(at 0.27 0.452 270)
			(size 0.4 0.5)
			(layers "B.Cu" "B.Mask" "B.Paste")
			(roundrect_rratio 0.25)
			(net 6 "Vtt")
			(pinfunction "R3.2")
			(pintype "passive")
		)
		(pad "7" smd roundrect
			(at -0.272 0.452 270)
			(size 0.4 0.5)
			(layers "B.Cu" "B.Mask" "B.Paste")
			(roundrect_rratio 0.25)
			(net 6 "Vtt")
			(pinfunction "R2.2")
			(pintype "passive")
		)
		(pad "8" smd roundrect
			(at -0.802 0.452 270)
			(size 0.4 0.5)
			(layers "B.Cu" "B.Mask" "B.Paste")
			(roundrect_rratio 0.25)
			(net 6 "Vtt")
			(pinfunction "R1.2")
			(pintype "passive")
		)
	)
	(footprint "antmicro-footprints:C_0603_1608Metric"
		(layer "B.Cu")
		(at 124.57 97.78 -90)
		(descr "Capacitor SMD 0603")
		(tags "capacitor 0603")
		(property "Reference" "C86"
			(at -0.89 0.99 90)
			(layer "B.SilkS")
			(effects
				(font
					(size 0.65 0.65)
					(thickness 0.15)
				)
				(justify left bottom mirror)
			)
		)
		(property "Value" "C_10u_0603"
			(at 0 -1.6 90)
			(layer "B.Fab")
			(hide yes)
			(effects
				(font
					(size 0.7 0.7)
					(thickness 0.15)
				)
				(justify left bottom mirror)
			)
		)
		(property "Datasheet" "https://www.murata.com/products/productdetail?partno=GRM188R61A106KE69%23"
			(at 0 0 270)
			(layer "F.Fab")
			(hide yes)
			(effects
				(font
					(size 1.27 1.27)
					(thickness 0.15)
				)
			)
		)
		(property "Description" "SMD Multilayer Ceramic Capacitor, 10 µF, 10 V, 0603 [1608 Metric], ± 10%, X5R, GRM Series"
			(at 0 0 270)
			(layer "F.Fab")
			(hide yes)
			(effects
				(font
					(size 1.27 1.27)
					(thickness 0.15)
				)
			)
		)
		(property "Author" "Antmicro"
			(at 26.74 222.3 0)
			(layer "B.Fab")
			(hide yes)
			(effects
				(font
					(size 1 1)
					(thickness 0.15)
				)
				(justify mirror)
			)
		)
		(property "License" "Apache-2.0"
			(at 26.74 222.3 0)
			(layer "B.Fab")
			(hide yes)
			(effects
				(font
					(size 1 1)
					(thickness 0.15)
				)
				(justify mirror)
			)
		)
		(property "MPN" "GRM188R61A106KE69D"
			(at 26.74 222.3 0)
			(layer "B.Fab")
			(hide yes)
			(effects
				(font
					(size 1 1)
					(thickness 0.15)
				)
				(justify mirror)
			)
		)
		(property "Manufacturer" "Murata"
			(at 26.74 222.3 0)
			(layer "B.Fab")
			(hide yes)
			(effects
				(font
					(size 1 1)
					(thickness 0.15)
				)
				(justify mirror)
			)
		)
		(property "Val" "10u"
			(at 26.74 222.3 0)
			(layer "B.Fab")
			(hide yes)
			(effects
				(font
					(size 1 1)
					(thickness 0.15)
				)
				(justify mirror)
			)
		)
		(property "Voltage" ""
			(at 26.74 222.3 0)
			(layer "B.Fab")
			(hide yes)
			(effects
				(font
					(size 1 1)
					(thickness 0.15)
				)
				(justify mirror)
			)
		)
		(property "Dielectric" "template_dielectric"
			(at 0 0 270)
			(unlocked yes)
			(layer "B.Fab")
			(hide yes)
			(effects
				(font
					(size 1 1)
					(thickness 0.15)
				)
				(justify mirror)
			)
		)
		(sheetname "/FPGA Power/")
		(sheetfile "FPGA_Power.kicad_sch")
		(attr smd)
		(fp_line
			(start -0.15 0.4)
			(end 0.15 0.4)
			(stroke
				(width 0.15)
				(type solid)
			)
			(layer "B.SilkS")
		)
		(fp_line
			(start -0.15 -0.4)
			(end 0.15 -0.4)
			(stroke
				(width 0.15)
				(type solid)
			)
			(layer "B.SilkS")
		)
		(fp_rect
			(start -1.25 0.65)
			(end 1.25 -0.65)
			(stroke
				(width 0.05)
				(type solid)
			)
			(fill no)
			(layer "B.CrtYd")
		)
		(fp_rect
			(start -0.8 0.4)
			(end 0.8 -0.4)
			(stroke
				(width 0.15)
				(type solid)
			)
			(fill no)
			(layer "B.Fab")
		)
		(fp_text user "Author: Antmicro"
			(at -1.682 -4.894 90)
			(layer "B.Fab")
			(effects
				(font
					(size 0.7 0.7)
					(thickness 0.15)
				)
				(justify left bottom mirror)
			)
		)
		(fp_text user "${REFERENCE}"
			(at -1.682 -3.895 90)
			(layer "B.Fab")
			(effects
				(font
					(size 0.7 0.7)
					(thickness 0.15)
				)
				(justify left bottom mirror)
			)
		)
		(fp_text user "License: Apache-2.0"
			(at -1.682 -5.895 90)
			(layer "B.Fab")
			(effects
				(font
					(size 0.7 0.7)
					(thickness 0.15)
				)
				(justify left bottom mirror)
			)
		)
		(pad "1" smd roundrect
			(at -0.7 0 270)
			(size 0.8 1)
			(layers "B.Cu" "B.Mask" "B.Paste")
			(roundrect_rratio 0.2)
			(net 1 "GND")
			(pintype "passive")
		)
		(pad "2" smd roundrect
			(at 0.7 0 270)
			(size 0.8 1)
			(layers "B.Cu" "B.Mask" "B.Paste")
			(roundrect_rratio 0.2)
			(net 4 "1V0_Power")
			(pintype "passive")
		)
	)
	(footprint "antmicro-footprints:C_0603_1608Metric"
		(layer "B.Cu")
		(at 130.51 57.35 90)
		(descr "Capacitor SMD 0603")
		(tags "capacitor 0603")
		(property "Reference" "C5"
			(at -0.69 -0.88 90)
			(layer "B.SilkS")
			(effects
				(font
					(size 0.65 0.65)
					(thickness 0.15)
				)
				(justify right bottom mirror)
			)
		)
		(property "Value" "C_22u_0603"
			(at 0 -1.6 90)
			(layer "B.Fab")
			(hide yes)
			(effects
				(font
					(size 0.7 0.7)
					(thickness 0.15)
				)
				(justify right bottom mirror)
			)
		)
		(property "Datasheet" "https://www.murata.com/products/productdetail?partno=GRM188R60J226MEA0%23"
			(at 0 0 90)
			(layer "F.Fab")
			(hide yes)
			(effects
				(font
					(size 1.27 1.27)
					(thickness 0.15)
				)
			)
		)
		(property "Description" "SMD Multilayer Ceramic Capacitor, 22 µF, 6.3 V, 0603 [1608 Metric], ± 20%, X5R, GRM Series"
			(at 0 0 90)
			(layer "F.Fab")
			(hide yes)
			(effects
				(font
					(size 1.27 1.27)
					(thickness 0.15)
				)
			)
		)
		(property "Author" "Antmicro"
			(at 187.86 -73.16 0)
			(layer "B.Fab")
			(hide yes)
			(effects
				(font
					(size 1 1)
					(thickness 0.15)
				)
				(justify mirror)
			)
		)
		(property "Dielectric" ""
			(at 187.86 -73.16 0)
			(layer "B.Fab")
			(hide yes)
			(effects
				(font
					(size 1 1)
					(thickness 0.15)
				)
				(justify mirror)
			)
		)
		(property "License" "Apache-2.0"
			(at 187.86 -73.16 0)
			(layer "B.Fab")
			(hide yes)
			(effects
				(font
					(size 1 1)
					(thickness 0.15)
				)
				(justify mirror)
			)
		)
		(property "MPN" "GRM188R60J226MEA0D"
			(at 187.86 -73.16 0)
			(layer "B.Fab")
			(hide yes)
			(effects
				(font
					(size 1 1)
					(thickness 0.15)
				)
				(justify mirror)
			)
		)
		(property "Manufacturer" "Murata"
			(at 187.86 -73.16 0)
			(layer "B.Fab")
			(hide yes)
			(effects
				(font
					(size 1 1)
					(thickness 0.15)
				)
				(justify mirror)
			)
		)
		(property "Val" "22u"
			(at 187.86 -73.16 0)
			(layer "B.Fab")
			(hide yes)
			(effects
				(font
					(size 1 1)
					(thickness 0.15)
				)
				(justify mirror)
			)
		)
		(property "Voltage" ""
			(at 187.86 -73.16 0)
			(layer "B.Fab")
			(hide yes)
			(effects
				(font
					(size 1 1)
					(thickness 0.15)
				)
				(justify mirror)
			)
		)
		(sheetname "/Power Supply/")
		(sheetfile "supply.kicad_sch")
		(attr smd)
		(fp_line
			(start -0.15 -0.4)
			(end 0.15 -0.4)
			(stroke
				(width 0.15)
				(type solid)
			)
			(layer "B.SilkS")
		)
		(fp_line
			(start -0.15 0.4)
			(end 0.15 0.4)
			(stroke
				(width 0.15)
				(type solid)
			)
			(layer "B.SilkS")
		)
		(fp_rect
			(start -1.25 0.65)
			(end 1.25 -0.65)
			(stroke
				(width 0.05)
				(type solid)
			)
			(fill no)
			(layer "B.CrtYd")
		)
		(fp_rect
			(start -0.8 0.4)
			(end 0.8 -0.4)
			(stroke
				(width 0.15)
				(type solid)
			)
			(fill no)
			(layer "B.Fab")
		)
		(fp_text user "License: Apache-2.0"
			(at -1.682 -5.895 270)
			(layer "B.Fab")
			(effects
				(font
					(size 0.7 0.7)
					(thickness 0.15)
				)
				(justify left bottom mirror)
			)
		)
		(fp_text user "Author: Antmicro"
			(at -1.682 -4.894 270)
			(layer "B.Fab")
			(effects
				(font
					(size 0.7 0.7)
					(thickness 0.15)
				)
				(justify left bottom mirror)
			)
		)
		(fp_text user "${REFERENCE}"
			(at -1.682 -3.895 270)
			(layer "B.Fab")
			(effects
				(font
					(size 0.7 0.7)
					(thickness 0.15)
				)
				(justify left bottom mirror)
			)
		)
		(pad "1" smd roundrect
			(at -0.7 0 90)
			(size 0.8 1)
			(layers "B.Cu" "B.Mask" "B.Paste")
			(roundrect_rratio 0.2)
			(net 1 "GND")
			(pintype "passive")
		)
		(pad "2" smd roundrect
			(at 0.7 0 90)
			(size 0.8 1)
			(layers "B.Cu" "B.Mask" "B.Paste")
			(roundrect_rratio 0.2)
			(net 60 "Net-(U1-DDQ)")
			(pintype "passive")
		)
	)
	(footprint "antmicro-footprints:R_0402_1005Metric"
		(layer "B.Cu")
		(at 162.43 102.865 90)
		(descr "Resistor SMD 0402")
		(tags "resistor SMD 0402")
		(property "Reference" "R2"
			(at 0.825 1.3 270)
			(layer "B.SilkS")
			(effects
				(font
					(size 0.65 0.65)
					(thickness 0.15)
				)
				(justify left bottom mirror)
			)
		)
		(property "Value" "R_10k_0402"
			(at 0 -1.4 270)
			(layer "B.Fab")
			(hide yes)
			(effects
				(font
					(size 0.7 0.7)
					(thickness 0.15)
				)
				(justify left bottom mirror)
			)
		)
		(property "Datasheet" "https://www.bourns.com/docs/product-datasheets/cr.pdf"
			(at 0 0 90)
			(layer "F.Fab")
			(hide yes)
			(effects
				(font
					(size 1.27 1.27)
					(thickness 0.15)
				)
			)
		)
		(property "Description" "SMD Chip Resistor, 10 kohm, ± 1%, 62.5 mW, 0402 [1005 Metric], Thick Film, General Purpose"
			(at 0 0 90)
			(layer "F.Fab")
			(hide yes)
			(effects
				(font
					(size 1.27 1.27)
					(thickness 0.15)
				)
			)
		)
		(property "Author" "Antmicro"
			(at 265.295 -59.565 0)
			(layer "B.Fab")
			(hide yes)
			(effects
				(font
					(size 1 1)
					(thickness 0.15)
				)
				(justify mirror)
			)
		)
		(property "License" "Apache-2.0"
			(at 265.295 -59.565 0)
			(layer "B.Fab")
			(hide yes)
			(effects
				(font
					(size 1 1)
					(thickness 0.15)
				)
				(justify mirror)
			)
		)
		(property "MPN" "CR0402-FX-1002GLF"
			(at 265.295 -59.565 0)
			(layer "B.Fab")
			(hide yes)
			(effects
				(font
					(size 1 1)
					(thickness 0.15)
				)
				(justify mirror)
			)
		)
		(property "Manufacturer" "Bourns"
			(at 265.295 -59.565 0)
			(layer "B.Fab")
			(hide yes)
			(effects
				(font
					(size 1 1)
					(thickness 0.15)
				)
				(justify mirror)
			)
		)
		(property "Tolerance" "1%"
			(at 265.295 -59.565 0)
			(layer "B.Fab")
			(hide yes)
			(effects
				(font
					(size 1 1)
					(thickness 0.15)
				)
				(justify mirror)
			)
		)
		(property "Val" "10k"
			(at 265.295 -59.565 0)
			(layer "B.Fab")
			(hide yes)
			(effects
				(font
					(size 1 1)
					(thickness 0.15)
				)
				(justify mirror)
			)
		)
		(sheetname "/Power Supply/")
		(sheetfile "supply.kicad_sch")
		(attr smd)
		(fp_rect
			(start -0.925 0.47)
			(end 0.925 -0.47)
			(stroke
				(width 0.05)
				(type default)
			)
			(fill no)
			(layer "B.CrtYd")
		)
		(fp_rect
			(start -0.5 0.25)
			(end 0.5 -0.25)
			(stroke
				(width 0.15)
				(type solid)
			)
			(fill no)
			(layer "B.Fab")
		)
		(fp_text user "${REFERENCE}"
			(at -0.95 -3.168 270)
			(layer "B.Fab")
			(effects
				(font
					(size 0.7 0.7)
					(thickness 0.15)
				)
				(justify left bottom mirror)
			)
		)
		(fp_text user "Author: Antmicro"
			(at -0.95 -4.169 270)
			(layer "B.Fab")
			(effects
				(font
					(size 0.7 0.7)
					(thickness 0.15)
				)
				(justify left bottom mirror)
			)
		)
		(fp_text user "License: Apache-2.0"
			(at -0.95 -5.169 270)
			(layer "B.Fab")
			(effects
				(font
					(size 0.7 0.7)
					(thickness 0.15)
				)
				(justify left bottom mirror)
			)
		)
		(pad "1" smd roundrect
			(at -0.48 0 90)
			(size 0.59 0.64)
			(layers "B.Cu" "B.Mask" "B.Paste")
			(roundrect_rratio 0.25)
			(net 141 "/Power Supply/VREF_0V45")
			(pintype "passive")
		)
		(pad "2" smd roundrect
			(at 0.48 0 90)
			(size 0.59 0.64)
			(layers "B.Cu" "B.Mask" "B.Paste")
			(roundrect_rratio 0.25)
			(net 14 "+5V")
			(pintype "passive")
		)
	)
)
